#ISCELL
  mstr_symbols cad_note *
  *
#ISCELL
  mstr_symbols intel_corp_bpage *
  *
#ISCELL
  mstr_standard offpage *
  page97_i22
#CELL
  mstr_discrete res *
  page97_i33
#ISCELL
  mstr_standard offpage *
  page97_i34
#ISCELL
  mstr_symbols pvccio_cpu0 *
  page97_i41
#CELL
  mstr_discrete res *
  page97_i42
#CELL
  mstr_discrete res *
  page97_i44
#ISCELL
  mstr_symbols pvccio_cpu0 *
  page97_i71
#CELL
  mstr_discrete res *
  page97_i72
#ISCELL
  mstr_standard offpage *
  page97_i74
#CELL
  mstr_discrete res *
  page97_i76
#ISCELL
  mstr_standard offpage *
  page97_i77
#ISCELL
  mstr_symbols pvccio_cpu1 *
  page97_i78
#CELL
  mstr_discrete res *
  page97_i80
#CELL
  mstr_discrete res *
  page97_i81
#ISCELL
  mstr_symbols gnd *
  page97_i82
#ISCELL
  mstr_standard offpage *
  page97_i83
#ISCELL
  mstr_standard offpage *
  page97_i84
#ISCELL
  mstr_symbols pvccio_cpu0 *
  page97_i85
